# T6G (Grand Teton) — schematic netlist excerpt (pin names and nets, part order shuffled) for the footprints in the layout excerpt that follows; sources: Cadence DE-HDL packaged netlist, KiCad conversion of 04192023_DAF0TMB3IC0_F0TG_MB_C_brd_V02_OCP.brd

C1769  Q_CAP  0.1UF 25V 10% X7R  pkg 0402  page 130 : A = P3V3_AUX ; B = GND
R1025  Q_RES  0 5% CHIP  pkg 0201LF  page 287 : A = SMB_RT_CPU0_P1_R_SCL ; B = SMB_RT_CPU0_P1_R2_SCL
R4508  Q_RES  33.2 1% CHIP  pkg 0402LF  page 150 : A = SMB_1_PLD_3V3AUX_SCL ; B = SMB_1_PLD_3V3AUX_SCL_R3

(kicad_pcb
	(version 20260206)
	(generator "pcbnew")
	(generator_version "10.0")
	(general
		(thickness 1.6)
		(legacy_teardrops no)
	)
	(paper "A4")
	(title_block
		(title "04192023_DAF0TMB3IC0_F0TG_MB_C_brd_V02_OCP.brd")
		(comment 1 "Grand Teton / footprints 6457-6459 of 8354")
	)
	(layers
		(0 "F.Cu" signal "TOP")
		(4 "In1.Cu" signal "GND")
		(6 "In2.Cu" signal "IN1")
		(8 "In3.Cu" signal "GND1")
		(10 "In4.Cu" signal "IN2")
		(12 "In5.Cu" signal "GND2")
		(14 "In6.Cu" signal "IN3")
		(16 "In7.Cu" signal "GND3")
		(18 "In8.Cu" signal "VCC")
		(20 "In9.Cu" signal "VCC1")
		(22 "In10.Cu" signal "GND4")
		(24 "In11.Cu" signal "IN4")
		(26 "In12.Cu" signal "GND5")
		(28 "In13.Cu" signal "IN5")
		(30 "In14.Cu" signal "GND6")
		(32 "In15.Cu" signal "IN6")
		(34 "In16.Cu" signal "GND7")
		(2 "B.Cu" signal "BOTTOM")
		(9 "F.Adhes" user "F.Adhesive")
		(11 "B.Adhes" user "B.Adhesive")
		(13 "F.Paste" user "Package Geometry/Pastemask Top")
		(15 "B.Paste" user "Package Geometry/Pastemask Bottom")
		(5 "F.SilkS" user "Ref Des/Silkscreen Top")
		(7 "B.SilkS" user "Ref Des/Silkscreen Bottom")
		(1 "F.Mask" user "Board Geometry/Soldermask Top")
		(3 "B.Mask" user "Board Geometry/Soldermask Bottom")
		(17 "Dwgs.User" user "User.Drawings")
		(19 "Cmts.User" user "User.Comments")
		(21 "Eco1.User" user "User.Eco1")
		(23 "Eco2.User" user "User.Eco2")
		(25 "Edge.Cuts" user "Board Geometry/Outline")
		(27 "Margin" user)
		(31 "F.CrtYd" user "Package Geometry/Place Bound Top")
		(29 "B.CrtYd" user "Package Geometry/Place Bound Bottom")
		(35 "F.Fab" user "Ref Des/Assembly Top")
		(33 "B.Fab" user "Ref Des/Assembly Bottom")
	)
	(footprint ""
		(layer "B.Cu")
		(at 162.489388 -13.651738 180)
		(property "Reference" "R4508"
			(at 0 0 0)
			(layer "B.SilkS")
			(hide yes)
			(effects
				(font
					(size 1.27 1.27)
				)
				(justify mirror)
			)
		)
		(property "Value" ""
			(at 0 0 0)
			(layer "B.Fab")
			(effects
				(font
					(size 1.27 1.27)
				)
				(justify mirror)
			)
		)
		(duplicate_pad_numbers_are_jumpers no)
		(fp_line
			(start 0.7874 0.4064)
			(end 0.7874 -0.4064)
			(stroke
				(width 0.1524)
				(type default)
			)
			(layer "B.SilkS")
		)
		(fp_line
			(start 0.7874 -0.4064)
			(end -0.7874 -0.4064)
			(stroke
				(width 0.1524)
				(type default)
			)
			(layer "B.SilkS")
		)
		(fp_line
			(start -0.7874 0.4064)
			(end 0.7874 0.4064)
			(stroke
				(width 0.1524)
				(type default)
			)
			(layer "B.SilkS")
		)
		(fp_line
			(start -0.7874 -0.4064)
			(end -0.7874 0.4064)
			(stroke
				(width 0.1524)
				(type default)
			)
			(layer "B.SilkS")
		)
		(fp_line
			(start 0.67945 0.3048)
			(end 0.67945 -0.305054)
			(stroke
				(width 0.1)
				(type default)
			)
			(layer "B.Fab")
		)
		(fp_line
			(start 0.67945 -0.305054)
			(end 0.12065 -0.305054)
			(stroke
				(width 0.1)
				(type default)
			)
			(layer "B.Fab")
		)
		(fp_line
			(start 0.12065 0.3048)
			(end 0.67945 0.3048)
			(stroke
				(width 0.1)
				(type default)
			)
			(layer "B.Fab")
		)
		(fp_line
			(start 0.12065 0.2794)
			(end 0.12065 0.3048)
			(stroke
				(width 0.1)
				(type default)
			)
			(layer "B.Fab")
		)
		(fp_line
			(start 0.12065 -0.2794)
			(end -0.12065 -0.2794)
			(stroke
				(width 0.1)
				(type default)
			)
			(layer "B.Fab")
		)
		(fp_line
			(start 0.12065 -0.305054)
			(end 0.12065 -0.2794)
			(stroke
				(width 0.1)
				(type default)
			)
			(layer "B.Fab")
		)
		(fp_line
			(start -0.120396 0.3048)
			(end -0.120396 0.2794)
			(stroke
				(width 0.1)
				(type default)
			)
			(layer "B.Fab")
		)
		(fp_line
			(start -0.120396 0.2794)
			(end 0.12065 0.2794)
			(stroke
				(width 0.1)
				(type default)
			)
			(layer "B.Fab")
		)
		(fp_line
			(start -0.12065 -0.2794)
			(end -0.12065 -0.3048)
			(stroke
				(width 0.1)
				(type default)
			)
			(layer "B.Fab")
		)
		(fp_line
			(start -0.12065 -0.3048)
			(end -0.67945 -0.3048)
			(stroke
				(width 0.1)
				(type default)
			)
			(layer "B.Fab")
		)
		(fp_line
			(start -0.67945 0.3048)
			(end -0.120396 0.3048)
			(stroke
				(width 0.1)
				(type default)
			)
			(layer "B.Fab")
		)
		(fp_line
			(start -0.67945 -0.3048)
			(end -0.67945 0.3048)
			(stroke
				(width 0.1)
				(type default)
			)
			(layer "B.Fab")
		)
		(pad "1" smd circle
			(at 0.40005 0)
			(size 0 0)
			(layers "B.Cu" "B.Mask" "B.Paste")
			(net "SMB_1_PLD_3V3AUX_SCL")
		)
		(pad "2" smd circle
			(at -0.40005 0)
			(size 0 0)
			(layers "B.Cu" "B.Mask" "B.Paste")
			(net "SMB_1_PLD_3V3AUX_SCL_R3")
		)
	)
	(footprint ""
		(layer "B.Cu")
		(at 178.881532 -414.283144 180)
		(property "Reference" "C1769"
			(at 0 0 0)
			(layer "B.SilkS")
			(hide yes)
			(effects
				(font
					(size 1.27 1.27)
				)
				(justify mirror)
			)
		)
		(property "Value" ""
			(at 0 0 0)
			(layer "B.Fab")
			(effects
				(font
					(size 1.27 1.27)
				)
				(justify mirror)
			)
		)
		(duplicate_pad_numbers_are_jumpers no)
		(fp_line
			(start 0.7874 0.4064)
			(end 0.7874 -0.4064)
			(stroke
				(width 0.1524)
				(type default)
			)
			(layer "B.SilkS")
		)
		(fp_line
			(start 0.7874 -0.4064)
			(end -0.7874 -0.4064)
			(stroke
				(width 0.1524)
				(type default)
			)
			(layer "B.SilkS")
		)
		(fp_line
			(start -0.7874 0.4064)
			(end 0.7874 0.4064)
			(stroke
				(width 0.1524)
				(type default)
			)
			(layer "B.SilkS")
		)
		(fp_line
			(start -0.7874 -0.4064)
			(end -0.7874 0.4064)
			(stroke
				(width 0.1524)
				(type default)
			)
			(layer "B.SilkS")
		)
		(fp_line
			(start 0.67945 0.3048)
			(end 0.67945 -0.305054)
			(stroke
				(width 0.1)
				(type default)
			)
			(layer "B.Fab")
		)
		(fp_line
			(start 0.67945 -0.305054)
			(end 0.12065 -0.305054)
			(stroke
				(width 0.1)
				(type default)
			)
			(layer "B.Fab")
		)
		(fp_line
			(start 0.12065 0.3048)
			(end 0.67945 0.3048)
			(stroke
				(width 0.1)
				(type default)
			)
			(layer "B.Fab")
		)
		(fp_line
			(start 0.12065 0.2794)
			(end 0.12065 0.3048)
			(stroke
				(width 0.1)
				(type default)
			)
			(layer "B.Fab")
		)
		(fp_line
			(start 0.12065 -0.2794)
			(end -0.12065 -0.2794)
			(stroke
				(width 0.1)
				(type default)
			)
			(layer "B.Fab")
		)
		(fp_line
			(start 0.12065 -0.305054)
			(end 0.12065 -0.2794)
			(stroke
				(width 0.1)
				(type default)
			)
			(layer "B.Fab")
		)
		(fp_line
			(start -0.120396 0.3048)
			(end -0.120396 0.2794)
			(stroke
				(width 0.1)
				(type default)
			)
			(layer "B.Fab")
		)
		(fp_line
			(start -0.120396 0.2794)
			(end 0.12065 0.2794)
			(stroke
				(width 0.1)
				(type default)
			)
			(layer "B.Fab")
		)
		(fp_line
			(start -0.12065 -0.2794)
			(end -0.12065 -0.3048)
			(stroke
				(width 0.1)
				(type default)
			)
			(layer "B.Fab")
		)
		(fp_line
			(start -0.12065 -0.3048)
			(end -0.67945 -0.3048)
			(stroke
				(width 0.1)
				(type default)
			)
			(layer "B.Fab")
		)
		(fp_line
			(start -0.67945 0.3048)
			(end -0.120396 0.3048)
			(stroke
				(width 0.1)
				(type default)
			)
			(layer "B.Fab")
		)
		(fp_line
			(start -0.67945 -0.3048)
			(end -0.67945 0.3048)
			(stroke
				(width 0.1)
				(type default)
			)
			(layer "B.Fab")
		)
		(pad "1" smd circle
			(at 0.40005 0)
			(size 0 0)
			(layers "B.Cu" "B.Mask" "B.Paste")
			(net "P3V3_AUX")
		)
		(pad "2" smd circle
			(at -0.40005 0)
			(size 0 0)
			(layers "B.Cu" "B.Mask" "B.Paste")
			(net "GND")
		)
	)
	(footprint ""
		(layer "B.Cu")
		(at 233.807 -338.582 180)
		(property "Reference" "R1025"
			(at 0 0 0)
			(layer "B.SilkS")
			(hide yes)
			(effects
				(font
					(size 1.27 1.27)
				)
				(justify mirror)
			)
		)
		(property "Value" ""
			(at 0 0 0)
			(layer "B.Fab")
			(effects
				(font
					(size 1.27 1.27)
				)
				(justify mirror)
			)
		)
		(duplicate_pad_numbers_are_jumpers no)
		(fp_line
			(start 0.32512 0.175006)
			(end 0.32512 -0.175006)
			(stroke
				(width 0.1)
				(type default)
			)
			(layer "B.Fab")
		)
		(fp_line
			(start 0.32512 -0.175006)
			(end -0.32512 -0.175006)
			(stroke
				(width 0.1)
				(type default)
			)
			(layer "B.Fab")
		)
		(fp_line
			(start -0.32512 0.175006)
			(end 0.32512 0.175006)
			(stroke
				(width 0.1)
				(type default)
			)
			(layer "B.Fab")
		)
		(fp_line
			(start -0.32512 -0.175006)
			(end -0.32512 0.175006)
			(stroke
				(width 0.1)
				(type default)
			)
			(layer "B.Fab")
		)
		(pad "1" smd rect
			(at 0.2667 0)
			(size 0.3048 0.381)
			(layers "B.Cu" "B.Mask" "B.Paste")
			(net "SMB_RT_CPU0_P1_R_SCL")
		)
		(pad "2" smd rect
			(at -0.2667 0 180)
			(size 0.3048 0.381)
			(layers "B.Cu" "B.Mask" "B.Paste")
			(net "SMB_RT_CPU0_P1_R2_SCL")
		)
	)
)
